(kicad_pcb
	(version 20260206)
	(generator "pcbnew")
	(generator_version "10.0")
	(general
		(thickness 1.21888)
		(legacy_teardrops no)
	)
	(paper "A4")
	(title_block
		(title "timecard-proto-v0 — Timingcard_PCB.PcbDoc")
		(comment 1 "Time Appliance Project (Time Card) / footprints 57-71 of 167")
	)
	(layers
		(0 "F.Cu" signal "TOP")
		(4 "In1.Cu" signal "SGND")
		(6 "In2.Cu" signal "IN1")
		(8 "In3.Cu" signal "IN2")
		(10 "In4.Cu" signal "SGND1")
		(2 "B.Cu" signal "BOTTOM")
		(9 "F.Adhes" user "F.Adhesive")
		(11 "B.Adhes" user "B.Adhesive")
		(13 "F.Paste" user "Top Paste")
		(15 "B.Paste" user "Bottom Paste")
		(5 "F.SilkS" user "Top Overlay")
		(7 "B.SilkS" user "Bottom Overlay")
		(1 "F.Mask" user "Top Solder")
		(3 "B.Mask" user "Bottom Solder")
		(17 "Dwgs.User" user "User.Drawings")
		(19 "Cmts.User" user "User.Comments")
		(21 "Eco1.User" user "User.Eco1")
		(23 "Eco2.User" user "User.Eco2")
		(25 "Edge.Cuts" user)
		(27 "Margin" user)
		(31 "F.CrtYd" user "Top Courtyard")
		(29 "B.CrtYd" user "Bottom Courtyard")
		(35 "F.Fab" user "Top Component Center")
		(33 "B.Fab" user "Bottom Component Center")
	)
	(footprint "Passives:DIOM6959X26N"
		(layer "F.Cu")
		(at 85.027595 137.5646 180)
		(property "Reference" "D18"
			(at 4.1402 4.097655 0)
			(unlocked yes)
			(layer "F.SilkS")
			(effects
				(font
					(size 0.762 0.762)
					(thickness 0.2286)
				)
				(justify left bottom)
			)
		)
		(property "Value" "SMCJ6.5CA"
			(at 4.2545 -5.91439 0)
			(unlocked yes)
			(layer "F.SilkS")
			(hide yes)
			(effects
				(font
					(size 1.524 1.524)
					(thickness 0.254)
				)
				(justify left bottom)
			)
		)
		(sheetname "USER_IO")
		(sheetfile "USER_IO.kicad_sch")
		(duplicate_pad_numbers_are_jumpers no)
		(fp_line
			(start 3.6 3.15)
			(end -3.6 3.15)
			(stroke
				(width 0.2)
				(type solid)
			)
			(layer "F.SilkS")
		)
		(fp_line
			(start 3.6 1.975)
			(end 3.6 3.15)
			(stroke
				(width 0.2)
				(type solid)
			)
			(layer "F.SilkS")
		)
		(fp_line
			(start 3.6 -3.15)
			(end 3.6 -1.975)
			(stroke
				(width 0.2)
				(type solid)
			)
			(layer "F.SilkS")
		)
		(fp_line
			(start 3.6 -3.15)
			(end -3.6 -3.15)
			(stroke
				(width 0.2)
				(type solid)
			)
			(layer "F.SilkS")
		)
		(fp_line
			(start -3.6 1.975)
			(end -3.6 3.15)
			(stroke
				(width 0.2)
				(type solid)
			)
			(layer "F.SilkS")
		)
		(fp_line
			(start -3.6 -3.15)
			(end -3.6 -1.975)
			(stroke
				(width 0.2)
				(type solid)
			)
			(layer "F.SilkS")
		)
		(fp_circle
			(center -4.25 -2.125)
			(end -4.25 -2)
			(stroke
				(width 0.25)
				(type solid)
			)
			(fill no)
			(layer "F.SilkS")
		)
		(pad "A" smd rect
			(at 2.85 0 270)
			(size 3.15 2.45)
			(layers "F.Cu" "F.Mask" "F.Paste")
			(net "ANT4")
		)
		(pad "K" smd rect
			(at -2.85 0 270)
			(size 3.15 2.45)
			(layers "F.Cu" "F.Mask" "F.Paste")
			(net "GND")
		)
	)
	(footprint "Vault:CAPC1608X87X45ML20T05"
		(layer "F.Cu")
		(at 219.588595 92.6786 180)
		(property "Reference" "C12"
			(at 4.2 0.106655 0)
			(unlocked yes)
			(layer "F.SilkS")
			(effects
				(font
					(size 0.762 0.762)
					(thickness 0.2286)
				)
				(justify left bottom)
			)
		)
		(property "Value" "0.1uF"
			(at -12.7889 -3.09499 0)
			(unlocked yes)
			(layer "F.SilkS")
			(hide yes)
			(effects
				(font
					(size 1.524 1.524)
					(thickness 0.254)
				)
				(justify left bottom)
			)
		)
		(sheetname "POWER")
		(sheetfile "POWER.kicad_sch")
		(duplicate_pad_numbers_are_jumpers no)
		(pad "1" smd rect
			(at -0.7 0 270)
			(size 1.1 1.05)
			(layers "F.Cu" "F.Mask" "F.Paste")
			(net "GND")
		)
		(pad "2" smd rect
			(at 0.7 0 270)
			(size 1.1 1.05)
			(layers "F.Cu" "F.Mask" "F.Paste")
			(net "+3.3V")
		)
	)
	(footprint "Capacitors:CAPC2012X14N"
		(layer "F.Cu")
		(at 168.720595 89.0506 90)
		(property "Reference" "C72"
			(at 1.98169 0.690065 90)
			(unlocked yes)
			(layer "F.SilkS")
			(effects
				(font
					(size 0.762 0.762)
					(thickness 0.2286)
				)
				(justify left bottom)
			)
		)
		(property "Value" "CAP_0805_22UF_16V"
			(at -3.52679 -1.5875 0)
			(unlocked yes)
			(layer "F.SilkS")
			(hide yes)
			(effects
				(font
					(size 1.524 1.524)
					(thickness 0.254)
				)
				(justify left bottom)
			)
		)
		(sheetname "MAC")
		(sheetfile "MAC.kicad_sch")
		(duplicate_pad_numbers_are_jumpers no)
		(fp_line
			(start -0.762 -0.9652)
			(end 0.762 -0.9652)
			(stroke
				(width 0.1524)
				(type solid)
			)
			(layer "F.SilkS")
		)
		(fp_line
			(start -0.762 0.9652)
			(end 0.762 0.9652)
			(stroke
				(width 0.1524)
				(type solid)
			)
			(layer "F.SilkS")
		)
		(pad "1" smd rect
			(at -0.9 0 180)
			(size 1.45 1.15)
			(layers "F.Cu" "F.Mask" "F.Paste")
			(net "GND")
		)
		(pad "2" smd rect
			(at 0.9 0 180)
			(size 1.45 1.15)
			(layers "F.Cu" "F.Mask" "F.Paste")
			(net "NetC72_2")
		)
	)
	(footprint "Capacitors:CAPC2012X14N"
		(layer "F.Cu")
		(at 227.775595 124.4836 180)
		(property "Reference" "C13"
			(at -1.94991 -0.690055 0)
			(unlocked yes)
			(layer "F.SilkS")
			(effects
				(font
					(size 0.762 0.762)
					(thickness 0.2286)
				)
				(justify left bottom)
			)
		)
		(property "Value" "CAP_0805_10UF_25V"
			(at 7.4295 -0.98679 0)
			(unlocked yes)
			(layer "F.SilkS")
			(hide yes)
			(effects
				(font
					(size 1.524 1.524)
					(thickness 0.254)
				)
				(justify left bottom)
			)
		)
		(sheetname "POWER")
		(sheetfile "POWER.kicad_sch")
		(duplicate_pad_numbers_are_jumpers no)
		(fp_line
			(start 0.762 0.9652)
			(end -0.762 0.9652)
			(stroke
				(width 0.1524)
				(type solid)
			)
			(layer "F.SilkS")
		)
		(fp_line
			(start 0.762 -0.9652)
			(end -0.762 -0.9652)
			(stroke
				(width 0.1524)
				(type solid)
			)
			(layer "F.SilkS")
		)
		(pad "1" smd rect
			(at -0.9 0 270)
			(size 1.45 1.15)
			(layers "F.Cu" "F.Mask" "F.Paste")
			(net "+5.0V")
		)
		(pad "2" smd rect
			(at 0.9 0 270)
			(size 1.45 1.15)
			(layers "F.Cu" "F.Mask" "F.Paste")
			(net "GND")
		)
	)
	(footprint "Resistors:RESC2012X50N"
		(layer "F.Cu")
		(at 143.574595 66.4446 90)
		(property "Reference" "R21"
			(at -3.934 0.407345 90)
			(unlocked yes)
			(layer "F.SilkS")
			(effects
				(font
					(size 0.762 0.762)
					(thickness 0.2286)
				)
				(justify left bottom)
			)
		)
		(property "Value" "CRCW080533R0FKEA"
			(at -3.52679 -1.5875 0)
			(unlocked yes)
			(layer "F.SilkS")
			(hide yes)
			(effects
				(font
					(size 1.524 1.524)
					(thickness 0.254)
				)
				(justify left bottom)
			)
		)
		(sheetname "PCIe_JTAG")
		(sheetfile "PCIe_JTAG.kicad_sch")
		(duplicate_pad_numbers_are_jumpers no)
		(fp_line
			(start 0 -0.762)
			(end 0 0.762)
			(stroke
				(width 0.1524)
				(type solid)
			)
			(layer "F.SilkS")
		)
		(pad "1" smd rect
			(at -1 0 180)
			(size 1.45 0.95)
			(layers "F.Cu" "F.Mask" "F.Paste")
			(net "FPGA_TDI")
		)
		(pad "2" smd rect
			(at 1 0 180)
			(size 1.45 0.95)
			(layers "F.Cu" "F.Mask" "F.Paste")
			(net "NetR21_2")
		)
	)
	(footprint "Miscellaneous Devices:J1-0603"
		(layer "F.Cu")
		(at 92.688595 56.1286 -90)
		(property "Reference" "R10"
			(at -0.575 1.349544 90)
			(unlocked yes)
			(layer "F.SilkS")
			(effects
				(font
					(face "Arial")
					(size 0.48006 0.48006)
					(thickness 0.254)
				)
			)
		)
		(property "Value" "GPS2TX"
			(at 2.581402 -9.103025 0)
			(unlocked yes)
			(layer "F.SilkS")
			(hide yes)
			(effects
				(font
					(size 1.524 1.524)
					(thickness 0.254)
				)
			)
		)
		(sheetname "GPS_IMU_SENSORS")
		(sheetfile "GPS_IMU_SENSORS.kicad_sch")
		(duplicate_pad_numbers_are_jumpers no)
		(fp_line
			(start 0.2 0.35)
			(end -0.2 0.35)
			(stroke
				(width 0.2)
				(type solid)
			)
			(layer "F.SilkS")
		)
		(fp_line
			(start 0.2 -0.35)
			(end -0.2 -0.35)
			(stroke
				(width 0.2)
				(type solid)
			)
			(layer "F.SilkS")
		)
		(pad "1" smd rect
			(at -0.75 0)
			(size 0.9 0.7)
			(layers "F.Cu" "F.Mask" "F.Paste")
			(net "GPS2_TX")
		)
		(pad "2" smd rect
			(at 0.75 0)
			(size 0.9 0.7)
			(layers "F.Cu" "F.Mask" "F.Paste")
			(net "NetJP1_3")
		)
	)
	(footprint "Passives:SOT65P210X110-3N"
		(layer "F.Cu")
		(at 140.907595 66.4446 -90)
		(property "Reference" "D7"
			(at 4.934 -0.474345 90)
			(unlocked yes)
			(layer "F.SilkS")
			(effects
				(font
					(size 0.762 0.762)
					(thickness 0.2286)
				)
				(justify left bottom)
			)
		)
		(property "Value" "BAT54SW"
			(at 3.88239 1.5875 0)
			(unlocked yes)
			(layer "F.SilkS")
			(hide yes)
			(effects
				(font
					(size 1.524 1.524)
					(thickness 0.254)
				)
				(justify left bottom)
			)
		)
		(sheetname "PCIe_JTAG")
		(sheetfile "PCIe_JTAG.kicad_sch")
		(duplicate_pad_numbers_are_jumpers no)
		(fp_line
			(start 0.675 1.1)
			(end -0.325 1.1)
			(stroke
				(width 0.2)
				(type solid)
			)
			(layer "F.SilkS")
		)
		(fp_line
			(start 0.675 1.1)
			(end 0.675 0.65)
			(stroke
				(width 0.2)
				(type solid)
			)
			(layer "F.SilkS")
		)
		(fp_line
			(start 0.675 -0.65)
			(end 0.675 -1.1)
			(stroke
				(width 0.2)
				(type solid)
			)
			(layer "F.SilkS")
		)
		(fp_line
			(start 0.675 -1.1)
			(end -0.325 -1.1)
			(stroke
				(width 0.2)
				(type solid)
			)
			(layer "F.SilkS")
		)
		(fp_circle
			(center -1.125 -1.45)
			(end -1.25 -1.45)
			(stroke
				(width 0.25)
				(type solid)
			)
			(fill no)
			(layer "F.SilkS")
		)
		(pad "1" smd rect
			(at -1.125 -0.65)
			(size 0.5 0.9)
			(layers "F.Cu" "F.Mask" "F.Paste")
			(net "GND")
		)
		(pad "2" smd rect
			(at -1.125 0.65)
			(size 0.5 0.9)
			(layers "F.Cu" "F.Mask" "F.Paste")
			(net "+3.3V")
		)
		(pad "3" smd rect
			(at 1.125 0)
			(size 0.5 0.9)
			(layers "F.Cu" "F.Mask" "F.Paste")
			(net "FPGA_TMS")
		)
	)
	(footprint "Vault:CAPC1608X87X45ML20T05"
		(layer "F.Cu")
		(at 214.059595 105.4336)
		(property "Reference" "C21"
			(at -4.371 0.538345 0)
			(unlocked yes)
			(layer "F.SilkS")
			(effects
				(font
					(size 0.762 0.762)
					(thickness 0.2286)
				)
				(justify left bottom)
			)
		)
		(property "Value" "0.1uF"
			(at 21.5011 -18.06321 0)
			(unlocked yes)
			(layer "F.SilkS")
			(hide yes)
			(effects
				(font
					(size 1.524 1.524)
					(thickness 0.254)
				)
				(justify left bottom)
			)
		)
		(sheetname "POWER")
		(sheetfile "POWER.kicad_sch")
		(duplicate_pad_numbers_are_jumpers no)
		(pad "1" smd rect
			(at -0.7 0 90)
			(size 1.1 1.05)
			(layers "F.Cu" "F.Mask" "F.Paste")
			(net "GND")
		)
		(pad "2" smd rect
			(at 0.7 0 90)
			(size 1.1 1.05)
			(layers "F.Cu" "F.Mask" "F.Paste")
			(net "NetC21_2")
		)
	)
	(footprint "Resistors:RESC2012X50N"
		(layer "F.Cu")
		(at 135.827595 66.4446 90)
		(property "Reference" "R19"
			(at -4.88269 0.639265 90)
			(unlocked yes)
			(layer "F.SilkS")
			(effects
				(font
					(size 0.762 0.762)
					(thickness 0.2286)
				)
				(justify left bottom)
			)
		)
		(property "Value" "CRCW080533R0FKEA"
			(at -3.52679 -1.5875 0)
			(unlocked yes)
			(layer "F.SilkS")
			(hide yes)
			(effects
				(font
					(size 1.524 1.524)
					(thickness 0.254)
				)
				(justify left bottom)
			)
		)
		(sheetname "PCIe_JTAG")
		(sheetfile "PCIe_JTAG.kicad_sch")
		(duplicate_pad_numbers_are_jumpers no)
		(fp_line
			(start 0 -0.762)
			(end 0 0.762)
			(stroke
				(width 0.1524)
				(type solid)
			)
			(layer "F.SilkS")
		)
		(pad "1" smd rect
			(at -1 0 180)
			(size 1.45 0.95)
			(layers "F.Cu" "F.Mask" "F.Paste")
			(net "FPGA_TDO")
		)
		(pad "2" smd rect
			(at 1 0 180)
			(size 1.45 0.95)
			(layers "F.Cu" "F.Mask" "F.Paste")
			(net "NetR19_2")
		)
	)
	(footprint "Capacitors:CAPC2012X14N"
		(layer "F.Cu")
		(at 219.393595 106.0686 -90)
		(property "Reference" "C5"
			(at 3.41 -0.488345 90)
			(unlocked yes)
			(layer "F.SilkS")
			(effects
				(font
					(size 0.762 0.762)
					(thickness 0.2286)
				)
				(justify left bottom)
			)
		)
		(property "Value" "CAP_0805_10UF_25V"
			(at -19.07921 -10.6045 0)
			(unlocked yes)
			(layer "F.SilkS")
			(hide yes)
			(effects
				(font
					(size 1.524 1.524)
					(thickness 0.254)
				)
				(justify left bottom)
			)
		)
		(sheetname "POWER")
		(sheetfile "POWER.kicad_sch")
		(duplicate_pad_numbers_are_jumpers no)
		(fp_line
			(start 0.762 0.9652)
			(end -0.762 0.9652)
			(stroke
				(width 0.1524)
				(type solid)
			)
			(layer "F.SilkS")
		)
		(fp_line
			(start 0.762 -0.9652)
			(end -0.762 -0.9652)
			(stroke
				(width 0.1524)
				(type solid)
			)
			(layer "F.SilkS")
		)
		(pad "1" smd rect
			(at -0.9 0)
			(size 1.45 1.15)
			(layers "F.Cu" "F.Mask" "F.Paste")
			(net "+12V")
		)
		(pad "2" smd rect
			(at 0.9 0)
			(size 1.45 1.15)
			(layers "F.Cu" "F.Mask" "F.Paste")
			(net "GND")
		)
	)
	(footprint "Vault:CAPC1608X87X45ML20T05"
		(layer "F.Cu")
		(at 201.988595 75.2786 180)
		(property "Reference" "C2"
			(at -1.23159 3.077655 180)
			(unlocked yes)
			(layer "F.SilkS")
			(effects
				(font
					(size 0.762 0.762)
					(thickness 0.2286)
				)
				(justify left bottom)
			)
		)
		(property "Value" "0.1uF"
			(at 0.7493 -3.01879 0)
			(unlocked yes)
			(layer "F.SilkS")
			(hide yes)
			(effects
				(font
					(size 1.524 1.524)
					(thickness 0.254)
				)
				(justify left bottom)
			)
		)
		(sheetname "POWER")
		(sheetfile "POWER.kicad_sch")
		(duplicate_pad_numbers_are_jumpers no)
		(pad "1" smd rect
			(at -0.7 0 270)
			(size 1.1 1.05)
			(layers "F.Cu" "F.Mask" "F.Paste")
			(net "GND")
		)
		(pad "2" smd rect
			(at 0.7 0 270)
			(size 1.1 1.05)
			(layers "F.Cu" "F.Mask" "F.Paste")
			(net "+12V")
		)
	)
	(footprint "Vault:CAPC1608X90X35NL10T15"
		(layer "F.Cu")
		(at 234.760595 112.1646 -90)
		(property "Reference" "C20"
			(at -1.336 -0.346345 90)
			(unlocked yes)
			(layer "F.SilkS")
			(effects
				(font
					(size 0.762 0.762)
					(thickness 0.2286)
				)
				(justify left bottom)
			)
		)
		(property "Value" "0.033uF"
			(at 3.34899 3.7211 0)
			(unlocked yes)
			(layer "F.SilkS")
			(hide yes)
			(effects
				(font
					(size 1.524 1.524)
					(thickness 0.254)
				)
				(justify left bottom)
			)
		)
		(sheetname "POWER")
		(sheetfile "POWER.kicad_sch")
		(duplicate_pad_numbers_are_jumpers no)
		(pad "1" smd rect
			(at -0.675 0)
			(size 0.95 0.85)
			(layers "F.Cu" "F.Mask" "F.Paste")
			(net "NetC20_1")
		)
		(pad "2" smd rect
			(at 0.675 0)
			(size 0.95 0.85)
			(layers "F.Cu" "F.Mask" "F.Paste")
			(net "NetC20_2")
		)
	)
	(footprint "Vault:W16-H2_L"
		(layer "F.Cu")
		(at 133.013595 81.5286)
		(property "Reference" "U3"
			(at -1.470995 -6.423069 0)
			(unlocked yes)
			(layer "F.SilkS")
			(effects
				(font
					(size 0.762 0.762)
					(thickness 0.254)
				)
			)
		)
		(property "Value" "DS3231SN"
			(at 0.59505 6.950202 0)
			(unlocked yes)
			(layer "F.SilkS")
			(hide yes)
			(effects
				(font
					(size 1.524 1.524)
					(thickness 0.254)
				)
			)
		)
		(sheetname "MAC")
		(sheetfile "MAC.kicad_sch")
		(duplicate_pad_numbers_are_jumpers no)
		(fp_line
			(start -3.1 -5.25)
			(end 3.1 -5.25)
			(stroke
				(width 0.2)
				(type solid)
			)
			(layer "F.SilkS")
		)
		(fp_line
			(start -3.1 5.25)
			(end -3.1 -5.25)
			(stroke
				(width 0.2)
				(type solid)
			)
			(layer "F.SilkS")
		)
		(fp_line
			(start -3.1 5.25)
			(end 3.1 5.25)
			(stroke
				(width 0.2)
				(type solid)
			)
			(layer "F.SilkS")
		)
		(fp_line
			(start 3.1 5.25)
			(end 3.1 -5.25)
			(stroke
				(width 0.2)
				(type solid)
			)
			(layer "F.SilkS")
		)
		(fp_circle
			(center -4.5 -5.295)
			(end -4.5 -5.42)
			(stroke
				(width 0.25)
				(type solid)
			)
			(fill no)
			(layer "F.SilkS")
		)
		(fp_circle
			(center -2.1 -4.25)
			(end -2.1 -4.55)
			(stroke
				(width 0.6)
				(type solid)
			)
			(fill no)
			(layer "F.SilkS")
		)
		(pad "1" smd oval
			(at -4.5 -4.445 90)
			(size 0.6 2)
			(layers "F.Cu" "F.Mask" "F.Paste")
		)
		(pad "2" smd oval
			(at -4.5 -3.175 90)
			(size 0.6 2)
			(layers "F.Cu" "F.Mask" "F.Paste")
			(net "+3.3V_CLEAN")
		)
		(pad "3" smd oval
			(at -4.5 -1.905 90)
			(size 0.6 2)
			(layers "F.Cu" "F.Mask" "F.Paste")
			(net "RTC_MFP")
		)
		(pad "4" smd oval
			(at -4.5 -0.635 90)
			(size 0.6 2)
			(layers "F.Cu" "F.Mask" "F.Paste")
		)
		(pad "5" smd oval
			(at -4.5 0.635 90)
			(size 0.6 2)
			(layers "F.Cu" "F.Mask" "F.Paste")
		)
		(pad "6" smd oval
			(at -4.5 1.905 90)
			(size 0.6 2)
			(layers "F.Cu" "F.Mask" "F.Paste")
		)
		(pad "7" smd oval
			(at -4.5 3.175 90)
			(size 0.6 2)
			(layers "F.Cu" "F.Mask" "F.Paste")
		)
		(pad "8" smd oval
			(at -4.5 4.445 90)
			(size 0.6 2)
			(layers "F.Cu" "F.Mask" "F.Paste")
		)
		(pad "9" smd oval
			(at 4.5 4.445 90)
			(size 0.6 2)
			(layers "F.Cu" "F.Mask" "F.Paste")
		)
		(pad "10" smd oval
			(at 4.5 3.175 90)
			(size 0.6 2)
			(layers "F.Cu" "F.Mask" "F.Paste")
		)
		(pad "11" smd oval
			(at 4.5 1.905 90)
			(size 0.6 2)
			(layers "F.Cu" "F.Mask" "F.Paste")
		)
		(pad "12" smd oval
			(at 4.5 0.635 90)
			(size 0.6 2)
			(layers "F.Cu" "F.Mask" "F.Paste")
		)
		(pad "13" smd oval
			(at 4.5 -0.635 90)
			(size 0.6 2)
			(layers "F.Cu" "F.Mask" "F.Paste")
			(net "GND")
		)
		(pad "14" smd oval
			(at 4.5 -1.905 90)
			(size 0.6 2)
			(layers "F.Cu" "F.Mask" "F.Paste")
			(net "NetBT1_2")
		)
		(pad "15" smd oval
			(at 4.5 -3.175 90)
			(size 0.6 2)
			(layers "F.Cu" "F.Mask" "F.Paste")
			(net "SDA")
		)
		(pad "16" smd oval
			(at 4.5 -4.445 90)
			(size 0.6 2)
			(layers "F.Cu" "F.Mask" "F.Paste")
			(net "SCL")
		)
	)
	(footprint "Miscellaneous Devices:J1-0603"
		(layer "F.Cu")
		(at 190.288595 55.0786 180)
		(property "Reference" "R36"
			(at -2.854 -0.126931 0)
			(unlocked yes)
			(layer "F.SilkS")
			(effects
				(font
					(size 0.762 0.762)
					(thickness 0.254)
				)
			)
		)
		(property "Value" "ERJ-3EKF1001V"
			(at -4.10075 -2.835402 0)
			(unlocked yes)
			(layer "F.SilkS")
			(hide yes)
			(effects
				(font
					(size 1.524 1.524)
					(thickness 0.254)
				)
			)
		)
		(sheetname "USER_IO")
		(sheetfile "USER_IO.kicad_sch")
		(duplicate_pad_numbers_are_jumpers no)
		(fp_line
			(start 0.2 0.35)
			(end -0.2 0.35)
			(stroke
				(width 0.2)
				(type solid)
			)
			(layer "F.SilkS")
		)
		(fp_line
			(start 0.2 -0.35)
			(end -0.2 -0.35)
			(stroke
				(width 0.2)
				(type solid)
			)
			(layer "F.SilkS")
		)
		(pad "1" smd rect
			(at -0.75 0 270)
			(size 0.9 0.7)
			(layers "F.Cu" "F.Mask" "F.Paste")
			(net "KEY2")
		)
		(pad "2" smd rect
			(at 0.75 0 270)
			(size 0.9 0.7)
			(layers "F.Cu" "F.Mask" "F.Paste")
			(net "NetR34_1")
		)
	)
	(footprint "Resistors:RESC1608X50N"
		(layer "F.Cu")
		(at 214.008795 98.0676 90)
		(property "Reference" "R5"
			(at 1.639 0.398145 90)
			(unlocked yes)
			(layer "F.SilkS")
			(effects
				(font
					(size 0.762 0.762)
					(thickness 0.2286)
				)
				(justify left bottom)
			)
		)
		(property "Value" "ERJ-3EKF2612V"
			(at -3.17119 -1.0033 0)
			(unlocked yes)
			(layer "F.SilkS")
			(hide yes)
			(effects
				(font
					(size 1.524 1.524)
					(thickness 0.254)
				)
				(justify left bottom)
			)
		)
		(sheetname "POWER")
		(sheetfile "POWER.kicad_sch")
		(duplicate_pad_numbers_are_jumpers no)
		(fp_line
			(start 0 -0.5)
			(end 0 0.5)
			(stroke
				(width 0.1524)
				(type solid)
			)
			(layer "F.SilkS")
		)
		(pad "1" smd rect
			(at -0.69 0 180)
			(size 1 0.72)
			(layers "F.Cu" "F.Mask" "F.Paste")
			(net "NetR5_1")
		)
		(pad "2" smd rect
			(at 0.69 0 180)
			(size 1 0.72)
			(layers "F.Cu" "F.Mask" "F.Paste")
			(net "+3.3V")
		)
	)
)
